# T6G (Grand Teton) — schematic netlist excerpt (pin names and nets, part order shuffled) for the footprints in the layout excerpt that follows; sources: Cadence DE-HDL packaged netlist, KiCad conversion of 04192023_DAF0TMB3IC0_F0TG_MB_C_brd_V02_OCP.brd

C410  Q_CAP  10UF 6.3V 20% X6S  pkg C0402  page 345 : A = P0V9_CPU1_RT2_2A ; B = GND
C2347  Q_CAP  22UF 4V 20% X6S  pkg C0402  page 73 : A = PVDDCR_CPU0_P1 ; B = GND

(kicad_pcb
	(version 20260206)
	(generator "pcbnew")
	(generator_version "10.0")
	(general
		(thickness 1.6)
		(legacy_teardrops no)
	)
	(paper "A4")
	(title_block
		(title "04192023_DAF0TMB3IC0_F0TG_MB_C_brd_V02_OCP.brd")
		(comment 1 "Grand Teton / footprints 6559-6560 of 8354")
	)
	(layers
		(0 "F.Cu" signal "TOP")
		(4 "In1.Cu" signal "GND")
		(6 "In2.Cu" signal "IN1")
		(8 "In3.Cu" signal "GND1")
		(10 "In4.Cu" signal "IN2")
		(12 "In5.Cu" signal "GND2")
		(14 "In6.Cu" signal "IN3")
		(16 "In7.Cu" signal "GND3")
		(18 "In8.Cu" signal "VCC")
		(20 "In9.Cu" signal "VCC1")
		(22 "In10.Cu" signal "GND4")
		(24 "In11.Cu" signal "IN4")
		(26 "In12.Cu" signal "GND5")
		(28 "In13.Cu" signal "IN5")
		(30 "In14.Cu" signal "GND6")
		(32 "In15.Cu" signal "IN6")
		(34 "In16.Cu" signal "GND7")
		(2 "B.Cu" signal "BOTTOM")
		(9 "F.Adhes" user "F.Adhesive")
		(11 "B.Adhes" user "B.Adhesive")
		(13 "F.Paste" user "Package Geometry/Pastemask Top")
		(15 "B.Paste" user "Package Geometry/Pastemask Bottom")
		(5 "F.SilkS" user "Ref Des/Silkscreen Top")
		(7 "B.SilkS" user "Ref Des/Silkscreen Bottom")
		(1 "F.Mask" user "Board Geometry/Soldermask Top")
		(3 "B.Mask" user "Board Geometry/Soldermask Bottom")
		(17 "Dwgs.User" user "User.Drawings")
		(19 "Cmts.User" user "User.Comments")
		(21 "Eco1.User" user "User.Eco1")
		(23 "Eco2.User" user "User.Eco2")
		(25 "Edge.Cuts" user "Board Geometry/Outline")
		(27 "Margin" user)
		(31 "F.CrtYd" user "Package Geometry/Place Bound Top")
		(29 "B.CrtYd" user "Package Geometry/Place Bound Bottom")
		(35 "F.Fab" user "Ref Des/Assembly Top")
		(33 "B.Fab" user "Ref Des/Assembly Bottom")
	)
	(footprint ""
		(layer "B.Cu")
		(at 147.018756 -390.560052 90)
		(property "Reference" "C410"
			(at 0 0 90)
			(layer "B.SilkS")
			(hide yes)
			(effects
				(font
					(size 1.27 1.27)
				)
				(justify mirror)
			)
		)
		(property "Value" ""
			(at 0 0 90)
			(layer "B.Fab")
			(effects
				(font
					(size 1.27 1.27)
				)
				(justify mirror)
			)
		)
		(duplicate_pad_numbers_are_jumpers no)
		(fp_line
			(start 0.7874 -0.4064)
			(end -0.7874 -0.4064)
			(stroke
				(width 0.1524)
				(type default)
			)
			(layer "B.SilkS")
		)
		(fp_line
			(start -0.7874 -0.4064)
			(end -0.7874 0.4064)
			(stroke
				(width 0.1524)
				(type default)
			)
			(layer "B.SilkS")
		)
		(fp_line
			(start 0.7874 0.4064)
			(end 0.7874 -0.4064)
			(stroke
				(width 0.1524)
				(type default)
			)
			(layer "B.SilkS")
		)
		(fp_line
			(start -0.7874 0.4064)
			(end 0.7874 0.4064)
			(stroke
				(width 0.1524)
				(type default)
			)
			(layer "B.SilkS")
		)
		(fp_line
			(start 0.67945 -0.305054)
			(end 0.12065 -0.305054)
			(stroke
				(width 0.1)
				(type default)
			)
			(layer "B.Fab")
		)
		(fp_line
			(start 0.12065 -0.305054)
			(end 0.12065 -0.2794)
			(stroke
				(width 0.1)
				(type default)
			)
			(layer "B.Fab")
		)
		(fp_line
			(start -0.12065 -0.3048)
			(end -0.67945 -0.3048)
			(stroke
				(width 0.1)
				(type default)
			)
			(layer "B.Fab")
		)
		(fp_line
			(start -0.67945 -0.3048)
			(end -0.67945 0.3048)
			(stroke
				(width 0.1)
				(type default)
			)
			(layer "B.Fab")
		)
		(fp_line
			(start 0.12065 -0.2794)
			(end -0.12065 -0.2794)
			(stroke
				(width 0.1)
				(type default)
			)
			(layer "B.Fab")
		)
		(fp_line
			(start -0.12065 -0.2794)
			(end -0.12065 -0.3048)
			(stroke
				(width 0.1)
				(type default)
			)
			(layer "B.Fab")
		)
		(fp_line
			(start 0.12065 0.2794)
			(end 0.12065 0.3048)
			(stroke
				(width 0.1)
				(type default)
			)
			(layer "B.Fab")
		)
		(fp_line
			(start -0.120396 0.2794)
			(end 0.12065 0.2794)
			(stroke
				(width 0.1)
				(type default)
			)
			(layer "B.Fab")
		)
		(fp_line
			(start 0.67945 0.3048)
			(end 0.67945 -0.305054)
			(stroke
				(width 0.1)
				(type default)
			)
			(layer "B.Fab")
		)
		(fp_line
			(start 0.12065 0.3048)
			(end 0.67945 0.3048)
			(stroke
				(width 0.1)
				(type default)
			)
			(layer "B.Fab")
		)
		(fp_line
			(start -0.120396 0.3048)
			(end -0.120396 0.2794)
			(stroke
				(width 0.1)
				(type default)
			)
			(layer "B.Fab")
		)
		(fp_line
			(start -0.67945 0.3048)
			(end -0.120396 0.3048)
			(stroke
				(width 0.1)
				(type default)
			)
			(layer "B.Fab")
		)
		(pad "1" smd circle
			(at 0.40005 0 270)
			(size 0 0)
			(layers "B.Cu" "B.Mask" "B.Paste")
			(net "P0V9_CPU1_RT2_2A")
		)
		(pad "2" smd circle
			(at -0.40005 0 270)
			(size 0 0)
			(layers "B.Cu" "B.Mask" "B.Paste")
			(net "GND")
		)
	)
	(footprint ""
		(layer "B.Cu")
		(at 110.177834 -248.916952 120)
		(property "Reference" "C2347"
			(at 0 0 120)
			(layer "B.SilkS")
			(hide yes)
			(effects
				(font
					(size 1.27 1.27)
				)
				(justify mirror)
			)
		)
		(property "Value" ""
			(at 0 0 120)
			(layer "B.Fab")
			(effects
				(font
					(size 1.27 1.27)
				)
				(justify mirror)
			)
		)
		(duplicate_pad_numbers_are_jumpers no)
		(fp_line
			(start 0.787516 -0.406438)
			(end -0.787425 -0.40652)
			(stroke
				(width 0.1524)
				(type default)
			)
			(layer "B.SilkS")
		)
		(fp_line
			(start 0.787425 0.40652)
			(end 0.787516 -0.406438)
			(stroke
				(width 0.1524)
				(type default)
			)
			(layer "B.SilkS")
		)
		(fp_line
			(start -0.787425 -0.40652)
			(end -0.787516 0.406438)
			(stroke
				(width 0.1524)
				(type default)
			)
			(layer "B.SilkS")
		)
		(fp_line
			(start -0.787516 0.406438)
			(end 0.787425 0.40652)
			(stroke
				(width 0.1524)
				(type default)
			)
			(layer "B.SilkS")
		)
		(fp_line
			(start 0.679475 -0.305158)
			(end 0.120732 -0.305125)
			(stroke
				(width 0.1)
				(type default)
			)
			(layer "B.Fab")
		)
		(fp_line
			(start 0.120732 -0.305125)
			(end 0.120554 -0.279418)
			(stroke
				(width 0.1)
				(type default)
			)
			(layer "B.Fab")
		)
		(fp_line
			(start 0.120554 -0.279418)
			(end -0.120587 -0.279326)
			(stroke
				(width 0.1)
				(type default)
			)
			(layer "B.Fab")
		)
		(fp_line
			(start -0.120536 -0.304813)
			(end -0.6795 -0.304908)
			(stroke
				(width 0.1)
				(type default)
			)
			(layer "B.Fab")
		)
		(fp_line
			(start -0.120587 -0.279326)
			(end -0.120536 -0.304813)
			(stroke
				(width 0.1)
				(type default)
			)
			(layer "B.Fab")
		)
		(fp_line
			(start 0.6795 0.304908)
			(end 0.679475 -0.305158)
			(stroke
				(width 0.1)
				(type default)
			)
			(layer "B.Fab")
		)
		(fp_line
			(start -0.6795 -0.304908)
			(end -0.679568 0.304811)
			(stroke
				(width 0.1)
				(type default)
			)
			(layer "B.Fab")
		)
		(fp_line
			(start 0.120587 0.279326)
			(end 0.120536 0.304813)
			(stroke
				(width 0.1)
				(type default)
			)
			(layer "B.Fab")
		)
		(fp_line
			(start 0.120536 0.304813)
			(end 0.6795 0.304908)
			(stroke
				(width 0.1)
				(type default)
			)
			(layer "B.Fab")
		)
		(fp_line
			(start -0.120334 0.279545)
			(end 0.120587 0.279326)
			(stroke
				(width 0.1)
				(type default)
			)
			(layer "B.Fab")
		)
		(fp_line
			(start -0.120258 0.304812)
			(end -0.120334 0.279545)
			(stroke
				(width 0.1)
				(type default)
			)
			(layer "B.Fab")
		)
		(fp_line
			(start -0.679568 0.304811)
			(end -0.120258 0.304812)
			(stroke
				(width 0.1)
				(type default)
			)
			(layer "B.Fab")
		)
		(pad "1" smd circle
			(at 0.40005 0 300)
			(size 0 0)
			(layers "B.Cu" "B.Mask" "B.Paste")
			(net "PVDDCR_CPU0_P1")
		)
		(pad "2" smd circle
			(at -0.40005 0 300)
			(size 0 0)
			(layers "B.Cu" "B.Mask" "B.Paste")
			(net "GND")
		)
	)
)
